(kicad_pcb
	(version 20241229)
	(generator "pcbnew")
	(generator_version "9.0")
	(general
		(thickness 1.6296)
		(legacy_teardrops no)
	)
	(paper "A3")
	(title_block
		(title "Thunderbolt to 10GbE adapter")
		(date "2026-04-21")
		(rev "1.1.0")
		(company "Antmicro Ltd")
		(comment 1 "www.antmicro.com")
		(comment 9 "footprint 288 of 703 (U14), pads 85-165 of 503")
	)
	(layers
		(0 "F.Cu" signal)
		(4 "In1.Cu" signal)
		(6 "In2.Cu" signal)
		(8 "In3.Cu" signal)
		(10 "In4.Cu" signal)
		(12 "In5.Cu" signal)
		(14 "In6.Cu" signal)
		(2 "B.Cu" signal)
		(9 "F.Adhes" user "F.Adhesive")
		(11 "B.Adhes" user "B.Adhesive")
		(13 "F.Paste" user)
		(15 "B.Paste" user)
		(5 "F.SilkS" user "F.Silkscreen")
		(7 "B.SilkS" user "B.Silkscreen")
		(1 "F.Mask" user)
		(3 "B.Mask" user)
		(17 "Dwgs.User" user "User.Drawings")
		(19 "Cmts.User" user "User.Comments")
		(21 "Eco1.User" user "User.Eco1")
		(23 "Eco2.User" user "User.Eco2")
		(25 "Edge.Cuts" user)
		(27 "Margin" user)
		(31 "F.CrtYd" user "F.Courtyard")
		(29 "B.CrtYd" user "B.Courtyard")
		(35 "F.Fab" user)
		(33 "B.Fab" user)
	)
	(footprint "antmicro-footprints:FCBGA-503_22x22mm_Layout21x24_P1mm"
		(layer "F.Cu")
		(at 151.005 81.499999 -90)
		(property "Reference" "U14"
			(at -11.499999 11.005 0)
			(layer "F.SilkS")
			(effects
				(font
					(size 0.7 0.7)
					(thickness 0.15)
				)
				(justify left bottom)
			)
		)
		(property "Value" "EZX710AT2_S_LMR5"
			(at -11.4 12.5 270)
			(layer "F.Fab")
			(effects
				(font
					(size 0.7 0.7)
					(thickness 0.15)
				)
				(justify left bottom)
			)
		)
		(property "Datasheet" "https://www.google.com/url?sa=t&source=web&rct=j&opi=89978449&url=https://cdrdv2-public.intel.com/596333/596333_X710-TM4_Datasheet_v_2_4.pdf&ved=2ahUKEwiSuv20_sCOAxXVCRAIHdxGO_UQFnoECBEQAQ&usg=AOvVaw1CjGyrGWE8ZvOdw4VBsY6U"
			(at 0 0 270)
			(layer "F.Fab")
			(effects
				(font
					(size 0.7 0.7)
					(thickness 0.15)
				)
				(justify left bottom)
			)
		)
		(property "Description" "Ethernet ICs Intel Ethernet Controller 10 Gigabit X7"
			(at 0 0 270)
			(layer "F.Fab")
			(effects
				(font
					(size 0.7 0.7)
					(thickness 0.15)
				)
				(justify left bottom)
			)
		)
		(property "MPN" "EZX710AT2 S LMR5"
			(at 0 0 270)
			(unlocked yes)
			(layer "F.Fab")
			(hide yes)
			(effects
				(font
					(size 1 1)
					(thickness 0.15)
				)
			)
		)
		(property "Manufacturer" "Intel"
			(at 0 0 270)
			(unlocked yes)
			(layer "F.Fab")
			(hide yes)
			(effects
				(font
					(size 1 1)
					(thickness 0.15)
				)
			)
		)
		(property "Author" "Antmicro"
			(at 0 0 270)
			(unlocked yes)
			(layer "F.Fab")
			(hide yes)
			(effects
				(font
					(size 1 1)
					(thickness 0.15)
				)
			)
		)
		(property "License" "Apache-2.0"
			(at 0 0 270)
			(unlocked yes)
			(layer "F.Fab")
			(hide yes)
			(effects
				(font
					(size 1 1)
					(thickness 0.15)
				)
			)
		)
		(sheetname "/X710-AT2 power/")
		(sheetfile "x710-at2-power.kicad_sch")
		(attr smd)
		(pad "AD4" smd circle
			(at -8.75 9.945 270)
			(size 0.5 0.5)
			(layers "F.Cu" "F.Mask" "F.Paste")
			(net 27 "/X710-AT2 PCIe/PCIe_{x4}_AC.TX0+")
			(pinfunction "PET_0_P")
			(pintype "output")
		)
		(pad "AD6" smd circle
			(at -7.75 9.945 270)
			(size 0.5 0.5)
			(layers "F.Cu" "F.Mask" "F.Paste")
			(net 23 "GND")
			(pinfunction "VSSA")
			(pintype "passive")
		)
		(pad "AD8" smd circle
			(at -6.75 9.945 270)
			(size 0.5 0.5)
			(layers "F.Cu" "F.Mask" "F.Paste")
			(net 29 "/X710-AT2 PCIe/PCIe_{x4}_AC.TX1+")
			(pinfunction "PET_1_P")
			(pintype "output")
		)
		(pad "AD10" smd circle
			(at -5.75 9.945 270)
			(size 0.5 0.5)
			(layers "F.Cu" "F.Mask" "F.Paste")
			(net 30 "/X710-AT2 PCIe/PCIe_{x4}_AC.TX1-")
			(pinfunction "PET_1_N")
			(pintype "output")
		)
		(pad "AD12" smd circle
			(at -4.75 9.945 270)
			(size 0.5 0.5)
			(layers "F.Cu" "F.Mask" "F.Paste")
			(net 23 "GND")
			(pinfunction "VSSA")
			(pintype "passive")
		)
		(pad "AD14" smd circle
			(at -3.75 9.945 270)
			(size 0.5 0.5)
			(layers "F.Cu" "F.Mask" "F.Paste")
			(net 31 "/X710-AT2 PCIe/PCIe_{x4}_AC.TX2+")
			(pinfunction "PET_2_P")
			(pintype "output")
		)
		(pad "AD16" smd circle
			(at -2.75 9.945 270)
			(size 0.5 0.5)
			(layers "F.Cu" "F.Mask" "F.Paste")
			(net 32 "/X710-AT2 PCIe/PCIe_{x4}_AC.TX2-")
			(pinfunction "PET_2_N")
			(pintype "output")
		)
		(pad "AD18" smd circle
			(at -1.75 9.945 270)
			(size 0.5 0.5)
			(layers "F.Cu" "F.Mask" "F.Paste")
			(net 23 "GND")
			(pinfunction "VSSA")
			(pintype "passive")
		)
		(pad "AD20" smd circle
			(at -0.75 9.945 270)
			(size 0.5 0.5)
			(layers "F.Cu" "F.Mask" "F.Paste")
			(net 33 "/X710-AT2 PCIe/PCIe_{x4}_AC.TX3+")
			(pinfunction "PET_3_P")
			(pintype "output")
		)
		(pad "AD22" smd circle
			(at 0.25 9.945 270)
			(size 0.5 0.5)
			(layers "F.Cu" "F.Mask" "F.Paste")
			(net 34 "/X710-AT2 PCIe/PCIe_{x4}_AC.TX3-")
			(pinfunction "PET_3_N")
			(pintype "output")
		)
		(pad "AD24" smd circle
			(at 1.25 9.945 270)
			(size 0.5 0.5)
			(layers "F.Cu" "F.Mask" "F.Paste")
			(net 23 "GND")
			(pinfunction "VSSA")
			(pintype "passive")
		)
		(pad "AD26" smd circle
			(at 2.25 9.945 270)
			(size 0.5 0.5)
			(layers "F.Cu" "F.Mask" "F.Paste")
			(net 487 "unconnected-(U14A-PET_4_P-PadAD26)")
			(pinfunction "PET_4_P")
			(pintype "output+no_connect")
		)
		(pad "AD28" smd circle
			(at 3.25 9.945 270)
			(size 0.5 0.5)
			(layers "F.Cu" "F.Mask" "F.Paste")
			(net 532 "unconnected-(U14A-PET_4_N-PadAD28)")
			(pinfunction "PET_4_N")
			(pintype "output+no_connect")
		)
		(pad "AD30" smd circle
			(at 4.25 9.945 270)
			(size 0.5 0.5)
			(layers "F.Cu" "F.Mask" "F.Paste")
			(net 23 "GND")
			(pinfunction "VSSA")
			(pintype "passive")
		)
		(pad "AD32" smd circle
			(at 5.25 9.945 270)
			(size 0.5 0.5)
			(layers "F.Cu" "F.Mask" "F.Paste")
			(net 536 "unconnected-(U14A-PET_5_N-PadAD32)")
			(pinfunction "PET_5_N")
			(pintype "output+no_connect")
		)
		(pad "AD34" smd circle
			(at 6.25 9.945 270)
			(size 0.5 0.5)
			(layers "F.Cu" "F.Mask" "F.Paste")
			(net 23 "GND")
			(pinfunction "VSSA")
			(pintype "passive")
		)
		(pad "AD36" smd circle
			(at 7.25 9.945 270)
			(size 0.5 0.5)
			(layers "F.Cu" "F.Mask" "F.Paste")
			(net 511 "unconnected-(U14A-PET_6_N-PadAD36)")
			(pinfunction "PET_6_N")
			(pintype "output+no_connect")
		)
		(pad "AD38" smd circle
			(at 8.25 9.945 270)
			(size 0.5 0.5)
			(layers "F.Cu" "F.Mask" "F.Paste")
			(net 23 "GND")
			(pinfunction "VSSA")
			(pintype "passive")
		)
		(pad "AD40" smd circle
			(at 9.25 9.945 270)
			(size 0.5 0.5)
			(layers "F.Cu" "F.Mask" "F.Paste")
			(net 516 "unconnected-(U14A-PET_7_N-PadAD40)")
			(pinfunction "PET_7_N")
			(pintype "output+no_connect")
		)
		(pad "AD42" smd circle
			(at 10.25 9.945 270)
			(size 0.5 0.5)
			(layers "F.Cu" "F.Mask" "F.Paste")
			(net 23 "GND")
			(pinfunction "VSSA")
			(pintype "passive")
		)
		(pad "B2" smd circle
			(at -9.75 -9.085 270)
			(size 0.5 0.5)
			(layers "F.Cu" "F.Mask" "F.Paste")
			(net 23 "GND")
			(pinfunction "VSSA")
			(pintype "passive")
		)
		(pad "B4" smd circle
			(at -8.75 -9.085 270)
			(size 0.5 0.5)
			(layers "F.Cu" "F.Mask" "F.Paste")
			(net 23 "GND")
			(pinfunction "VSSA")
			(pintype "passive")
		)
		(pad "B6" smd circle
			(at -7.75 -9.085 270)
			(size 0.5 0.5)
			(layers "F.Cu" "F.Mask" "F.Paste")
			(net 545 "unconnected-(U14B-SER1_RX_P-PadB6)")
			(pinfunction "SER1_RX_P")
			(pintype "input+no_connect")
		)
		(pad "B8" smd circle
			(at -6.75 -9.085 270)
			(size 0.5 0.5)
			(layers "F.Cu" "F.Mask" "F.Paste")
			(net 23 "GND")
			(pinfunction "VSSA")
			(pintype "passive")
		)
		(pad "B10" smd circle
			(at -5.75 -9.085 270)
			(size 0.5 0.5)
			(layers "F.Cu" "F.Mask" "F.Paste")
			(net 456 "unconnected-(U14B-SER1_TX_N-PadB10)")
			(pinfunction "SER1_TX_N")
			(pintype "output+no_connect")
		)
		(pad "B12" smd circle
			(at -4.75 -9.085 270)
			(size 0.5 0.5)
			(layers "F.Cu" "F.Mask" "F.Paste")
			(net 23 "GND")
			(pinfunction "VSSA")
			(pintype "passive")
		)
		(pad "B14" smd circle
			(at -3.75 -9.085 270)
			(size 0.5 0.5)
			(layers "F.Cu" "F.Mask" "F.Paste")
			(net 538 "unconnected-(U14B-SER0_RX_P-PadB14)")
			(pinfunction "SER0_RX_P")
			(pintype "input+no_connect")
		)
		(pad "B16" smd circle
			(at -2.75 -9.085 270)
			(size 0.5 0.5)
			(layers "F.Cu" "F.Mask" "F.Paste")
			(net 23 "GND")
			(pinfunction "VSSA")
			(pintype "passive")
		)
		(pad "B18" smd circle
			(at -1.75 -9.085 270)
			(size 0.5 0.5)
			(layers "F.Cu" "F.Mask" "F.Paste")
			(net 518 "unconnected-(U14B-SER0_TX_N-PadB18)")
			(pinfunction "SER0_TX_N")
			(pintype "output+no_connect")
		)
		(pad "B20" smd circle
			(at -0.75 -9.085 270)
			(size 0.5 0.5)
			(layers "F.Cu" "F.Mask" "F.Paste")
			(net 23 "GND")
			(pinfunction "VSSA")
			(pintype "passive")
		)
		(pad "B22" smd circle
			(at 0.25 -9.085 270)
			(size 0.5 0.5)
			(layers "F.Cu" "F.Mask" "F.Paste")
			(net 23 "GND")
			(pinfunction "AVSS")
			(pintype "passive")
		)
		(pad "B24" smd circle
			(at 1.25 -9.085 270)
			(size 0.5 0.5)
			(layers "F.Cu" "F.Mask" "F.Paste")
			(net 45 "/2xRJ45/Ethernet_P1.D1-")
			(pinfunction "P1_A_N")
			(pintype "bidirectional")
		)
		(pad "B26" smd circle
			(at 2.25 -9.085 270)
			(size 0.5 0.5)
			(layers "F.Cu" "F.Mask" "F.Paste")
			(net 47 "/2xRJ45/Ethernet_P1.D2+")
			(pinfunction "P1_B_P")
			(pintype "bidirectional")
		)
		(pad "B28" smd circle
			(at 3.25 -9.085 270)
			(size 0.5 0.5)
			(layers "F.Cu" "F.Mask" "F.Paste")
			(net 49 "/2xRJ45/Ethernet_P1.D3-")
			(pinfunction "P1_C_N")
			(pintype "bidirectional")
		)
		(pad "B30" smd circle
			(at 4.25 -9.085 270)
			(size 0.5 0.5)
			(layers "F.Cu" "F.Mask" "F.Paste")
			(net 50 "/2xRJ45/Ethernet_P1.D4+")
			(pinfunction "P1_D_P")
			(pintype "bidirectional")
		)
		(pad "B32" smd circle
			(at 5.25 -9.085 270)
			(size 0.5 0.5)
			(layers "F.Cu" "F.Mask" "F.Paste")
			(net 23 "GND")
			(pinfunction "AVSS")
			(pintype "passive")
		)
		(pad "B34" smd circle
			(at 6.25 -9.085 270)
			(size 0.5 0.5)
			(layers "F.Cu" "F.Mask" "F.Paste")
			(net 43 "/2xRJ45/Ethernet_P0.D4-")
			(pinfunction "P0_D_N")
			(pintype "bidirectional")
		)
		(pad "B36" smd circle
			(at 7.25 -9.085 270)
			(size 0.5 0.5)
			(layers "F.Cu" "F.Mask" "F.Paste")
			(net 44 "/2xRJ45/Ethernet_P0.D3+")
			(pinfunction "P0_C_P")
			(pintype "bidirectional")
		)
		(pad "B38" smd circle
			(at 8.25 -9.085 270)
			(size 0.5 0.5)
			(layers "F.Cu" "F.Mask" "F.Paste")
			(net 36 "/2xRJ45/Ethernet_P0.D2-")
			(pinfunction "P0_B_N")
			(pintype "bidirectional")
		)
		(pad "B40" smd circle
			(at 9.25 -9.085 270)
			(size 0.5 0.5)
			(layers "F.Cu" "F.Mask" "F.Paste")
			(net 42 "/2xRJ45/Ethernet_P0.D1+")
			(pinfunction "P0_A_P")
			(pintype "bidirectional")
		)
		(pad "B42" smd circle
			(at 10.25 -9.085 270)
			(size 0.5 0.5)
			(layers "F.Cu" "F.Mask" "F.Paste")
			(net 508 "unconnected-(U14G-RSVDB42_NC-PadB42)")
			(pinfunction "RSVDB42_NC")
			(pintype "passive+no_connect")
		)
		(pad "C1" smd circle
			(at -10.25 -8.22 270)
			(size 0.5 0.5)
			(layers "F.Cu" "F.Mask" "F.Paste")
			(net 24 "/X710-AT2 10GbE/25MHZ_OSC.+")
			(pinfunction "REFCLKIN_P")
			(pintype "input")
		)
		(pad "C3" smd circle
			(at -9.25 -8.22 270)
			(size 0.5 0.5)
			(layers "F.Cu" "F.Mask" "F.Paste")
			(net 26 "/X710-AT2 10GbE/25MHZ_OSC.-")
			(pinfunction "REFCLKIN_N")
			(pintype "input")
		)
		(pad "C5" smd circle
			(at -8.25 -8.22 270)
			(size 0.5 0.5)
			(layers "F.Cu" "F.Mask" "F.Paste")
			(net 23 "GND")
			(pinfunction "VSSA")
			(pintype "passive")
		)
		(pad "C7" smd circle
			(at -7.25 -8.22 270)
			(size 0.5 0.5)
			(layers "F.Cu" "F.Mask" "F.Paste")
			(net 23 "GND")
			(pinfunction "VSSA")
			(pintype "passive")
		)
		(pad "C9" smd circle
			(at -6.25 -8.22 270)
			(size 0.5 0.5)
			(layers "F.Cu" "F.Mask" "F.Paste")
			(net 23 "GND")
			(pinfunction "VSSA")
			(pintype "passive")
		)
		(pad "C11" smd circle
			(at -5.25 -8.22 270)
			(size 0.5 0.5)
			(layers "F.Cu" "F.Mask" "F.Paste")
			(net 23 "GND")
			(pinfunction "VSSA")
			(pintype "passive")
		)
		(pad "C13" smd circle
			(at -4.25 -8.22 270)
			(size 0.5 0.5)
			(layers "F.Cu" "F.Mask" "F.Paste")
			(net 23 "GND")
			(pinfunction "VSSA")
			(pintype "passive")
		)
		(pad "C15" smd circle
			(at -3.25 -8.22 270)
			(size 0.5 0.5)
			(layers "F.Cu" "F.Mask" "F.Paste")
			(net 23 "GND")
			(pinfunction "VSSA")
			(pintype "passive")
		)
		(pad "C17" smd circle
			(at -2.25 -8.22 270)
			(size 0.5 0.5)
			(layers "F.Cu" "F.Mask" "F.Paste")
			(net 23 "GND")
			(pinfunction "VSSA")
			(pintype "passive")
		)
		(pad "C19" smd circle
			(at -1.25 -8.22 270)
			(size 0.5 0.5)
			(layers "F.Cu" "F.Mask" "F.Paste")
			(net 23 "GND")
			(pinfunction "VSSA")
			(pintype "passive")
		)
		(pad "C21" smd circle
			(at -0.25 -8.22 270)
			(size 0.5 0.5)
			(layers "F.Cu" "F.Mask" "F.Paste")
			(net 562 "unconnected-(U14G-RSVDC21_NC-PadC21)")
			(pinfunction "RSVDC21_NC")
			(pintype "passive+no_connect")
		)
		(pad "C23" smd circle
			(at 0.75 -8.22 270)
			(size 0.5 0.5)
			(layers "F.Cu" "F.Mask" "F.Paste")
			(net 14 "P1_AVDDL")
			(pinfunction "P1_AVDDL")
			(pintype "power_in")
		)
		(pad "C25" smd circle
			(at 1.75 -8.22 270)
			(size 0.5 0.5)
			(layers "F.Cu" "F.Mask" "F.Paste")
			(net 14 "P1_AVDDL")
			(pinfunction "P1_AVDDL")
			(pintype "passive")
		)
		(pad "C27" smd circle
			(at 2.75 -8.22 270)
			(size 0.5 0.5)
			(layers "F.Cu" "F.Mask" "F.Paste")
			(net 14 "P1_AVDDL")
			(pinfunction "P1_AVDDL")
			(pintype "passive")
		)
		(pad "C29" smd circle
			(at 3.75 -8.22 270)
			(size 0.5 0.5)
			(layers "F.Cu" "F.Mask" "F.Paste")
			(net 14 "P1_AVDDL")
			(pinfunction "P1_AVDDL")
			(pintype "passive")
		)
		(pad "C31" smd circle
			(at 4.75 -8.22 270)
			(size 0.5 0.5)
			(layers "F.Cu" "F.Mask" "F.Paste")
			(net 23 "GND")
			(pinfunction "AVSS")
			(pintype "passive")
		)
		(pad "C33" smd circle
			(at 5.75 -8.22 270)
			(size 0.5 0.5)
			(layers "F.Cu" "F.Mask" "F.Paste")
			(net 5 "P0_AVDDL")
			(pinfunction "P0_AVDDL")
			(pintype "power_in")
		)
		(pad "C35" smd circle
			(at 6.75 -8.22 270)
			(size 0.5 0.5)
			(layers "F.Cu" "F.Mask" "F.Paste")
			(net 5 "P0_AVDDL")
			(pinfunction "P0_AVDDL")
			(pintype "passive")
		)
		(pad "C37" smd circle
			(at 7.75 -8.22 270)
			(size 0.5 0.5)
			(layers "F.Cu" "F.Mask" "F.Paste")
			(net 5 "P0_AVDDL")
			(pinfunction "P0_AVDDL")
			(pintype "passive")
		)
		(pad "C39" smd circle
			(at 8.75 -8.22 270)
			(size 0.5 0.5)
			(layers "F.Cu" "F.Mask" "F.Paste")
			(net 5 "P0_AVDDL")
			(pinfunction "P0_AVDDL")
			(pintype "passive")
		)
		(pad "C41" smd circle
			(at 9.75 -8.22 270)
			(size 0.5 0.5)
			(layers "F.Cu" "F.Mask" "F.Paste")
			(net 23 "GND")
			(pinfunction "AVSS")
			(pintype "passive")
		)
		(pad "D2" smd circle
			(at -9.75 -7.355 270)
			(size 0.5 0.5)
			(layers "F.Cu" "F.Mask" "F.Paste")
			(net 127 "/X710-AT2 Misc/~{DEV_DIS}")
			(pinfunction "~{DEV_DIS}")
			(pintype "tri_state")
		)
		(pad "D4" smd circle
			(at -8.75 -7.355 270)
			(size 0.5 0.5)
			(layers "F.Cu" "F.Mask" "F.Paste")
			(net 149 "/X710-AT2 Misc/REFCLK_SEL")
			(pinfunction "REFCLK_SEL")
			(pintype "input")
		)
		(pad "D6" smd circle
			(at -7.75 -7.355 270)
			(size 0.5 0.5)
			(layers "F.Cu" "F.Mask" "F.Paste")
			(net 23 "GND")
			(pinfunction "RSVDD6_VSS")
			(pintype "passive")
		)
		(pad "D8" smd circle
			(at -6.75 -7.355 270)
			(size 0.5 0.5)
			(layers "F.Cu" "F.Mask" "F.Paste")
			(net 101 "/X710-AT2 RSVD/RSVDD8_1P88V")
			(pinfunction "RSVDD8_1P88V")
			(pintype "passive")
		)
		(pad "D10" smd circle
			(at -5.75 -7.355 270)
			(size 0.5 0.5)
			(layers "F.Cu" "F.Mask" "F.Paste")
			(net 132 "/X710-AT2 Misc/XTAL_BYPASS")
			(pinfunction "XTAL_BYPASS")
			(pintype "passive")
		)
		(pad "D12" smd circle
			(at -4.75 -7.355 270)
			(size 0.5 0.5)
			(layers "F.Cu" "F.Mask" "F.Paste")
			(net 150 "/X710-AT2 Misc/~{PHY_RESET}")
			(pinfunction "~{RESET}")
			(pintype "input")
		)
		(pad "D14" smd circle
			(at -3.75 -7.355 270)
			(size 0.5 0.5)
			(layers "F.Cu" "F.Mask" "F.Paste")
			(net 23 "GND")
			(pinfunction "RSVDD14")
			(pintype "input")
		)
		(pad "D16" smd circle
			(at -2.75 -7.355 270)
			(size 0.5 0.5)
			(layers "F.Cu" "F.Mask" "F.Paste")
			(net 105 "/X710-AT2 Misc/PHY_TMS")
			(pinfunction "PHY_TMS")
			(pintype "input")
		)
		(pad "D18" smd circle
			(at -1.75 -7.355 270)
			(size 0.5 0.5)
			(layers "F.Cu" "F.Mask" "F.Paste")
			(net 88 "/X710-AT2 Misc/~{PHY_TRST}")
			(pinfunction "~{PHY_TRST}")
			(pintype "input")
		)
		(pad "D20" smd circle
			(at -0.75 -7.355 270)
			(size 0.5 0.5)
			(layers "F.Cu" "F.Mask" "F.Paste")
			(net 517 "unconnected-(U14G-RSVDD20_NC-PadD20)")
			(pinfunction "RSVDD20_NC")
			(pintype "passive+no_connect")
		)
		(pad "D22" smd circle
			(at 0.25 -7.355 270)
			(size 0.5 0.5)
			(layers "F.Cu" "F.Mask" "F.Paste")
			(net 23 "GND")
			(pinfunction "RSVDD22_VSS")
			(pintype "passive")
		)
		(pad "D24" smd circle
			(at 1.25 -7.355 270)
			(size 0.5 0.5)
			(layers "F.Cu" "F.Mask" "F.Paste")
			(net 23 "GND")
			(pinfunction "AVSS")
			(pintype "passive")
		)
		(pad "D26" smd circle
			(at 2.25 -7.355 270)
			(size 0.5 0.5)
			(layers "F.Cu" "F.Mask" "F.Paste")
			(net 23 "GND")
			(pinfunction "AVSS")
			(pintype "passive")
		)
		(pad "D28" smd circle
			(at 3.25 -7.355 270)
			(size 0.5 0.5)
			(layers "F.Cu" "F.Mask" "F.Paste")
			(net 23 "GND")
			(pinfunction "AVSS")
			(pintype "passive")
		)
		(pad "D30" smd circle
			(at 4.25 -7.355 270)
			(size 0.5 0.5)
			(layers "F.Cu" "F.Mask" "F.Paste")
			(net 10 "AVDDH")
			(pinfunction "BIAS_AVDDH")
			(pintype "power_in")
		)
		(pad "D32" smd circle
			(at 5.25 -7.355 270)
			(size 0.5 0.5)
			(layers "F.Cu" "F.Mask" "F.Paste")
			(net 566 "unconnected-(U14G-RSVDD32_NC-PadD32)")
			(pinfunction "RSVDD32_NC")
			(pintype "passive+no_connect")
		)
		(pad "D34" smd circle
			(at 6.25 -7.355 270)
			(size 0.5 0.5)
			(layers "F.Cu" "F.Mask" "F.Paste")
			(net 20 "XGB_AVDDH")
			(pinfunction "XGB_AVDDH")
			(pintype "power_in")
		)
		(pad "D36" smd circle
			(at 7.25 -7.355 270)
			(size 0.5 0.5)
			(layers "F.Cu" "F.Mask" "F.Paste")
			(net 23 "GND")
			(pinfunction "AVSS")
			(pintype "passive")
		)
		(pad "D38" smd circle
			(at 8.25 -7.355 270)
			(size 0.5 0.5)
			(layers "F.Cu" "F.Mask" "F.Paste")
			(net 23 "GND")
			(pinfunction "AVSS")
			(pintype "passive")
		)
	)
)
